(kicad_pcb
	(version 20260206)
	(generator "pcbnew")
	(generator_version "10.0")
	(general
		(thickness 1.6)
		(legacy_teardrops no)
	)
	(paper "A4")
	(title_block
		(title "04192023_DAF0TMB3IC0_F0TG_MB_C_brd_V02_OCP.brd")
		(comment 1 "Grand Teton / footprints 1044-1049 of 8354")
	)
	(layers
		(0 "F.Cu" signal "TOP")
		(4 "In1.Cu" signal "GND")
		(6 "In2.Cu" signal "IN1")
		(8 "In3.Cu" signal "GND1")
		(10 "In4.Cu" signal "IN2")
		(12 "In5.Cu" signal "GND2")
		(14 "In6.Cu" signal "IN3")
		(16 "In7.Cu" signal "GND3")
		(18 "In8.Cu" signal "VCC")
		(20 "In9.Cu" signal "VCC1")
		(22 "In10.Cu" signal "GND4")
		(24 "In11.Cu" signal "IN4")
		(26 "In12.Cu" signal "GND5")
		(28 "In13.Cu" signal "IN5")
		(30 "In14.Cu" signal "GND6")
		(32 "In15.Cu" signal "IN6")
		(34 "In16.Cu" signal "GND7")
		(2 "B.Cu" signal "BOTTOM")
		(9 "F.Adhes" user "F.Adhesive")
		(11 "B.Adhes" user "B.Adhesive")
		(13 "F.Paste" user "Package Geometry/Pastemask Top")
		(15 "B.Paste" user "Package Geometry/Pastemask Bottom")
		(5 "F.SilkS" user "Ref Des/Silkscreen Top")
		(7 "B.SilkS" user "Ref Des/Silkscreen Bottom")
		(1 "F.Mask" user "Board Geometry/Soldermask Top")
		(3 "B.Mask" user "Board Geometry/Soldermask Bottom")
		(17 "Dwgs.User" user "User.Drawings")
		(19 "Cmts.User" user "User.Comments")
		(21 "Eco1.User" user "User.Eco1")
		(23 "Eco2.User" user "User.Eco2")
		(25 "Edge.Cuts" user "Board Geometry/Outline")
		(27 "Margin" user)
		(31 "F.CrtYd" user "Package Geometry/Place Bound Top")
		(29 "B.CrtYd" user "Package Geometry/Place Bound Bottom")
		(35 "F.Fab" user "Ref Des/Assembly Top")
		(33 "B.Fab" user "Ref Des/Assembly Bottom")
	)
	(footprint ""
		(layer "F.Cu")
		(at 300.3804 -363.982)
		(property "Reference" "C5004"
			(at 0 0 0)
			(layer "F.SilkS")
			(hide yes)
			(effects
				(font
					(size 1.27 1.27)
				)
			)
		)
		(property "Value" ""
			(at 0 0 0)
			(layer "F.Fab")
			(effects
				(font
					(size 1.27 1.27)
				)
			)
		)
		(duplicate_pad_numbers_are_jumpers no)
		(fp_line
			(start -0.7874 -0.4064)
			(end 0.7874 -0.4064)
			(stroke
				(width 0.1524)
				(type default)
			)
			(layer "F.SilkS")
		)
		(fp_line
			(start -0.7874 0.4064)
			(end -0.7874 -0.4064)
			(stroke
				(width 0.1524)
				(type default)
			)
			(layer "F.SilkS")
		)
		(fp_line
			(start 0.7874 -0.4064)
			(end 0.7874 0.4064)
			(stroke
				(width 0.1524)
				(type default)
			)
			(layer "F.SilkS")
		)
		(fp_line
			(start 0.7874 0.4064)
			(end -0.7874 0.4064)
			(stroke
				(width 0.1524)
				(type default)
			)
			(layer "F.SilkS")
		)
		(fp_line
			(start -0.67945 -0.305054)
			(end -0.12065 -0.305054)
			(stroke
				(width 0.1)
				(type default)
			)
			(layer "F.Fab")
		)
		(fp_line
			(start -0.67945 0.3048)
			(end -0.67945 -0.305054)
			(stroke
				(width 0.1)
				(type default)
			)
			(layer "F.Fab")
		)
		(fp_line
			(start -0.12065 -0.305054)
			(end -0.12065 -0.2794)
			(stroke
				(width 0.1)
				(type default)
			)
			(layer "F.Fab")
		)
		(fp_line
			(start -0.12065 -0.2794)
			(end 0.12065 -0.2794)
			(stroke
				(width 0.1)
				(type default)
			)
			(layer "F.Fab")
		)
		(fp_line
			(start -0.12065 0.2794)
			(end -0.12065 0.3048)
			(stroke
				(width 0.1)
				(type default)
			)
			(layer "F.Fab")
		)
		(fp_line
			(start -0.12065 0.3048)
			(end -0.67945 0.3048)
			(stroke
				(width 0.1)
				(type default)
			)
			(layer "F.Fab")
		)
		(fp_line
			(start 0.120396 0.2794)
			(end -0.12065 0.2794)
			(stroke
				(width 0.1)
				(type default)
			)
			(layer "F.Fab")
		)
		(fp_line
			(start 0.120396 0.3048)
			(end 0.120396 0.2794)
			(stroke
				(width 0.1)
				(type default)
			)
			(layer "F.Fab")
		)
		(fp_line
			(start 0.12065 -0.3048)
			(end 0.67945 -0.3048)
			(stroke
				(width 0.1)
				(type default)
			)
			(layer "F.Fab")
		)
		(fp_line
			(start 0.12065 -0.2794)
			(end 0.12065 -0.3048)
			(stroke
				(width 0.1)
				(type default)
			)
			(layer "F.Fab")
		)
		(fp_line
			(start 0.67945 -0.3048)
			(end 0.67945 0.3048)
			(stroke
				(width 0.1)
				(type default)
			)
			(layer "F.Fab")
		)
		(fp_line
			(start 0.67945 0.3048)
			(end 0.120396 0.3048)
			(stroke
				(width 0.1)
				(type default)
			)
			(layer "F.Fab")
		)
		(pad "1" smd circle
			(at -0.40005 0)
			(size 0 0)
			(layers "F.Cu" "F.Mask" "F.Paste")
			(net "GND")
		)
		(pad "2" smd circle
			(at 0.40005 0)
			(size 0 0)
			(layers "F.Cu" "F.Mask" "F.Paste")
			(net "PWRGD_PVDDCR_CPU1_P0")
		)
	)
	(footprint ""
		(layer "F.Cu")
		(at 27.29611 -351.932748)
		(property "Reference" "PR368"
			(at 0 0 0)
			(layer "F.SilkS")
			(hide yes)
			(effects
				(font
					(size 1.27 1.27)
				)
			)
		)
		(property "Value" ""
			(at 0 0 0)
			(layer "F.Fab")
			(effects
				(font
					(size 1.27 1.27)
				)
			)
		)
		(duplicate_pad_numbers_are_jumpers no)
		(fp_line
			(start -0.7874 -0.4064)
			(end 0.7874 -0.4064)
			(stroke
				(width 0.1524)
				(type default)
			)
			(layer "F.SilkS")
		)
		(fp_line
			(start -0.7874 0.4064)
			(end -0.7874 -0.4064)
			(stroke
				(width 0.1524)
				(type default)
			)
			(layer "F.SilkS")
		)
		(fp_line
			(start 0.7874 -0.4064)
			(end 0.7874 0.4064)
			(stroke
				(width 0.1524)
				(type default)
			)
			(layer "F.SilkS")
		)
		(fp_line
			(start 0.7874 0.4064)
			(end -0.7874 0.4064)
			(stroke
				(width 0.1524)
				(type default)
			)
			(layer "F.SilkS")
		)
		(fp_line
			(start -0.67945 -0.305054)
			(end -0.12065 -0.305054)
			(stroke
				(width 0.1)
				(type default)
			)
			(layer "F.Fab")
		)
		(fp_line
			(start -0.67945 0.3048)
			(end -0.67945 -0.305054)
			(stroke
				(width 0.1)
				(type default)
			)
			(layer "F.Fab")
		)
		(fp_line
			(start -0.12065 -0.305054)
			(end -0.12065 -0.2794)
			(stroke
				(width 0.1)
				(type default)
			)
			(layer "F.Fab")
		)
		(fp_line
			(start -0.12065 -0.2794)
			(end 0.12065 -0.2794)
			(stroke
				(width 0.1)
				(type default)
			)
			(layer "F.Fab")
		)
		(fp_line
			(start -0.12065 0.2794)
			(end -0.12065 0.3048)
			(stroke
				(width 0.1)
				(type default)
			)
			(layer "F.Fab")
		)
		(fp_line
			(start -0.12065 0.3048)
			(end -0.67945 0.3048)
			(stroke
				(width 0.1)
				(type default)
			)
			(layer "F.Fab")
		)
		(fp_line
			(start 0.120396 0.2794)
			(end -0.12065 0.2794)
			(stroke
				(width 0.1)
				(type default)
			)
			(layer "F.Fab")
		)
		(fp_line
			(start 0.120396 0.3048)
			(end 0.120396 0.2794)
			(stroke
				(width 0.1)
				(type default)
			)
			(layer "F.Fab")
		)
		(fp_line
			(start 0.12065 -0.3048)
			(end 0.67945 -0.3048)
			(stroke
				(width 0.1)
				(type default)
			)
			(layer "F.Fab")
		)
		(fp_line
			(start 0.12065 -0.2794)
			(end 0.12065 -0.3048)
			(stroke
				(width 0.1)
				(type default)
			)
			(layer "F.Fab")
		)
		(fp_line
			(start 0.67945 -0.3048)
			(end 0.67945 0.3048)
			(stroke
				(width 0.1)
				(type default)
			)
			(layer "F.Fab")
		)
		(fp_line
			(start 0.67945 0.3048)
			(end 0.120396 0.3048)
			(stroke
				(width 0.1)
				(type default)
			)
			(layer "F.Fab")
		)
		(pad "1" smd circle
			(at -0.40005 0)
			(size 0 0)
			(layers "F.Cu" "F.Mask" "F.Paste")
			(net "PVDDIO_P1_LSET4")
		)
		(pad "2" smd circle
			(at 0.40005 0)
			(size 0 0)
			(layers "F.Cu" "F.Mask" "F.Paste")
			(net "GND")
		)
	)
	(footprint ""
		(layer "F.Cu")
		(at 97.902522 -67.038982 -90)
		(property "Reference" "PD109"
			(at 4.125722 -2.54254 90)
			(unlocked yes)
			(layer "F.SilkS")
			(effects
				(font
					(size 0.7874 0.5842)
					(thickness 0.1524)
				)
				(justify left)
			)
		)
		(property "Value" ""
			(at 0 0 270)
			(layer "F.Fab")
			(effects
				(font
					(size 1.27 1.27)
				)
			)
		)
		(duplicate_pad_numbers_are_jumpers no)
		(fp_line
			(start -3.400044 1.459992)
			(end -3.400044 -1.459992)
			(stroke
				(width 0.1524)
				(type default)
			)
			(layer "F.SilkS")
		)
		(fp_line
			(start 4.107942 1.459992)
			(end -3.400044 1.459992)
			(stroke
				(width 0.1524)
				(type default)
			)
			(layer "F.SilkS")
		)
		(fp_line
			(start -3.400044 -1.459992)
			(end 4.107942 -1.459992)
			(stroke
				(width 0.1524)
				(type default)
			)
			(layer "F.SilkS")
		)
		(fp_line
			(start 4.107942 -1.459992)
			(end 4.107942 1.459992)
			(stroke
				(width 0.1524)
				(type default)
			)
			(layer "F.SilkS")
		)
		(fp_rect
			(start 4.107942 1.459992)
			(end 3.308096 -1.459992)
			(stroke
				(width 0)
				(type default)
			)
			(fill yes)
			(layer "F.SilkS")
		)
		(fp_line
			(start -2.29997 1.459992)
			(end -2.29997 -1.459992)
			(stroke
				(width 0.1)
				(type default)
			)
			(layer "F.Fab")
		)
		(fp_line
			(start 2.29997 1.459992)
			(end -2.29997 1.459992)
			(stroke
				(width 0.1)
				(type default)
			)
			(layer "F.Fab")
		)
		(fp_line
			(start -2.29997 -1.459992)
			(end 2.29997 -1.459992)
			(stroke
				(width 0.1)
				(type default)
			)
			(layer "F.Fab")
		)
		(fp_line
			(start 2.29997 -1.459992)
			(end 2.29997 1.459992)
			(stroke
				(width 0.1)
				(type default)
			)
			(layer "F.Fab")
		)
		(fp_text user "-"
			(at 5.4102 0.29845 90)
			(unlocked yes)
			(layer "F.SilkS")
			(effects
				(font
					(size 1.905 1.4224)
					(thickness 0.1524)
				)
				(justify left)
			)
		)
		(fp_text user "+"
			(at -5.329174 -1.367536 270)
			(unlocked yes)
			(layer "F.SilkS")
			(effects
				(font
					(size 1.905 1.4224)
					(thickness 0.1524)
				)
				(justify left)
			)
		)
		(fp_text user "-"
			(at 5.4102 0.29845 90)
			(unlocked yes)
			(layer "F.Fab")
			(effects
				(font
					(size 1.905 1.4224)
					(thickness 0.1524)
				)
				(justify left)
			)
		)
		(fp_text user "+"
			(at -4.7752 -0.12065 270)
			(unlocked yes)
			(layer "F.Fab")
			(effects
				(font
					(size 1.905 1.4224)
					(thickness 0.1524)
				)
				(justify left)
			)
		)
		(pad "A" smd rect
			(at -1.999996 0)
			(size 1.7018 2.5146)
			(layers "F.Cu" "F.Mask" "F.Paste")
			(net "GND")
		)
		(pad "C" smd rect
			(at 1.999996 0)
			(size 1.7018 2.5146)
			(layers "F.Cu" "F.Mask" "F.Paste")
			(net "P3V3_OCP_V3_2_R")
		)
	)
	(footprint ""
		(layer "F.Cu")
		(at 98.52533 -39.465758 180)
		(property "Reference" "U217"
			(at 1.229868 1.844548 0)
			(unlocked yes)
			(layer "F.SilkS")
			(effects
				(font
					(size 0.7874 0.5842)
					(thickness 0.1524)
				)
				(justify left)
			)
		)
		(property "Value" ""
			(at 0 0 180)
			(layer "F.Fab")
			(effects
				(font
					(size 1.27 1.27)
				)
			)
		)
		(duplicate_pad_numbers_are_jumpers no)
		(fp_line
			(start 1.400048 1.100074)
			(end -1.400048 1.100074)
			(stroke
				(width 0.1524)
				(type default)
			)
			(layer "F.SilkS")
		)
		(fp_line
			(start 1.400048 -1.100074)
			(end 1.400048 1.100074)
			(stroke
				(width 0.1524)
				(type default)
			)
			(layer "F.SilkS")
		)
		(fp_line
			(start 1.400048 -1.100074)
			(end -1.400048 -1.100074)
			(stroke
				(width 0.1524)
				(type default)
			)
			(layer "F.SilkS")
		)
		(fp_line
			(start -1.400048 1.100074)
			(end -1.400048 -1.100074)
			(stroke
				(width 0.1524)
				(type default)
			)
			(layer "F.SilkS")
		)
		(fp_poly
			(pts
				(xy -0.51562 -2.307082) (xy -1.02362 -1.291082) (xy -1.53162 -2.307082)
			)
			(stroke
				(width 0)
				(type default)
			)
			(fill yes)
			(layer "F.SilkS")
		)
		(fp_line
			(start 0.674878 1.100074)
			(end -0.674878 1.100074)
			(stroke
				(width 0.1)
				(type default)
			)
			(layer "F.Fab")
		)
		(fp_line
			(start 0.674878 -1.100074)
			(end 0.674878 1.100074)
			(stroke
				(width 0.1)
				(type default)
			)
			(layer "F.Fab")
		)
		(fp_line
			(start -0.674878 1.100074)
			(end -0.674878 -1.100074)
			(stroke
				(width 0.1)
				(type default)
			)
			(layer "F.Fab")
		)
		(fp_line
			(start -0.674878 -1.100074)
			(end 0.674878 -1.100074)
			(stroke
				(width 0.1)
				(type default)
			)
			(layer "F.Fab")
		)
		(fp_poly
			(pts
				(xy -1.590548 -0.649986) (xy -2.606548 -1.157986) (xy -2.606548 -0.141986)
			)
			(stroke
				(width 0)
				(type default)
			)
			(fill yes)
			(layer "F.Fab")
		)
		(pad "1" smd rect
			(at -0.94996 -0.649986 90)
			(size 0.4318 0.6096)
			(layers "F.Cu" "F.Mask" "F.Paste")
			(net "PU_OCP_V3_2_WAKE_OE")
		)
		(pad "2" smd rect
			(at -0.94996 0 90)
			(size 0.4318 0.6096)
			(layers "F.Cu" "F.Mask" "F.Paste")
			(net "IRQ_LVC3_OCP_V3_2_WAKE_N")
		)
		(pad "3" smd rect
			(at -0.94996 0.649986 90)
			(size 0.4318 0.6096)
			(layers "F.Cu" "F.Mask" "F.Paste")
			(net "GND")
		)
		(pad "4" smd rect
			(at 0.94996 0.649986 90)
			(size 0.4318 0.6096)
			(layers "F.Cu" "F.Mask" "F.Paste")
			(net "OCP_V3_2_WAKE_BUFF_N")
		)
		(pad "5" smd rect
			(at 0.94996 -0.649986 90)
			(size 0.4318 0.6096)
			(layers "F.Cu" "F.Mask" "F.Paste")
			(net "P3V3_AUX")
		)
	)
	(footprint ""
		(layer "F.Cu")
		(at 212.993732 -116.732812 180)
		(property "Reference" "R136"
			(at 0 0 180)
			(layer "F.SilkS")
			(hide yes)
			(effects
				(font
					(size 1.27 1.27)
				)
			)
		)
		(property "Value" ""
			(at 0 0 180)
			(layer "F.Fab")
			(effects
				(font
					(size 1.27 1.27)
				)
			)
		)
		(duplicate_pad_numbers_are_jumpers no)
		(fp_line
			(start 0.7874 0.4064)
			(end -0.7874 0.4064)
			(stroke
				(width 0.1524)
				(type default)
			)
			(layer "F.SilkS")
		)
		(fp_line
			(start 0.7874 -0.4064)
			(end 0.7874 0.4064)
			(stroke
				(width 0.1524)
				(type default)
			)
			(layer "F.SilkS")
		)
		(fp_line
			(start -0.7874 0.4064)
			(end -0.7874 -0.4064)
			(stroke
				(width 0.1524)
				(type default)
			)
			(layer "F.SilkS")
		)
		(fp_line
			(start -0.7874 -0.4064)
			(end 0.7874 -0.4064)
			(stroke
				(width 0.1524)
				(type default)
			)
			(layer "F.SilkS")
		)
		(fp_line
			(start 0.67945 0.3048)
			(end 0.120396 0.3048)
			(stroke
				(width 0.1)
				(type default)
			)
			(layer "F.Fab")
		)
		(fp_line
			(start 0.67945 -0.3048)
			(end 0.67945 0.3048)
			(stroke
				(width 0.1)
				(type default)
			)
			(layer "F.Fab")
		)
		(fp_line
			(start 0.12065 -0.2794)
			(end 0.12065 -0.3048)
			(stroke
				(width 0.1)
				(type default)
			)
			(layer "F.Fab")
		)
		(fp_line
			(start 0.12065 -0.3048)
			(end 0.67945 -0.3048)
			(stroke
				(width 0.1)
				(type default)
			)
			(layer "F.Fab")
		)
		(fp_line
			(start 0.120396 0.3048)
			(end 0.120396 0.2794)
			(stroke
				(width 0.1)
				(type default)
			)
			(layer "F.Fab")
		)
		(fp_line
			(start 0.120396 0.2794)
			(end -0.12065 0.2794)
			(stroke
				(width 0.1)
				(type default)
			)
			(layer "F.Fab")
		)
		(fp_line
			(start -0.12065 0.3048)
			(end -0.67945 0.3048)
			(stroke
				(width 0.1)
				(type default)
			)
			(layer "F.Fab")
		)
		(fp_line
			(start -0.12065 0.2794)
			(end -0.12065 0.3048)
			(stroke
				(width 0.1)
				(type default)
			)
			(layer "F.Fab")
		)
		(fp_line
			(start -0.12065 -0.2794)
			(end 0.12065 -0.2794)
			(stroke
				(width 0.1)
				(type default)
			)
			(layer "F.Fab")
		)
		(fp_line
			(start -0.12065 -0.305054)
			(end -0.12065 -0.2794)
			(stroke
				(width 0.1)
				(type default)
			)
			(layer "F.Fab")
		)
		(fp_line
			(start -0.67945 0.3048)
			(end -0.67945 -0.305054)
			(stroke
				(width 0.1)
				(type default)
			)
			(layer "F.Fab")
		)
		(fp_line
			(start -0.67945 -0.305054)
			(end -0.12065 -0.305054)
			(stroke
				(width 0.1)
				(type default)
			)
			(layer "F.Fab")
		)
		(pad "1" smd circle
			(at -0.40005 0 180)
			(size 0 0)
			(layers "F.Cu" "F.Mask" "F.Paste")
			(net "FM_APML_MUX2_SEL")
		)
		(pad "2" smd circle
			(at 0.40005 0 180)
			(size 0 0)
			(layers "F.Cu" "F.Mask" "F.Paste")
			(net "GND")
		)
	)
	(footprint ""
		(layer "F.Cu")
		(at 176.911 -133.568948 90)
		(property "Reference" "R17"
			(at 0 0 90)
			(layer "F.SilkS")
			(hide yes)
			(effects
				(font
					(size 1.27 1.27)
				)
			)
		)
		(property "Value" ""
			(at 0 0 90)
			(layer "F.Fab")
			(effects
				(font
					(size 1.27 1.27)
				)
			)
		)
		(duplicate_pad_numbers_are_jumpers no)
		(fp_line
			(start 0.7874 -0.4064)
			(end 0.7874 0.4064)
			(stroke
				(width 0.1524)
				(type default)
			)
			(layer "F.SilkS")
		)
		(fp_line
			(start -0.7874 -0.4064)
			(end 0.7874 -0.4064)
			(stroke
				(width 0.1524)
				(type default)
			)
			(layer "F.SilkS")
		)
		(fp_line
			(start 0.7874 0.4064)
			(end -0.7874 0.4064)
			(stroke
				(width 0.1524)
				(type default)
			)
			(layer "F.SilkS")
		)
		(fp_line
			(start -0.7874 0.4064)
			(end -0.7874 -0.4064)
			(stroke
				(width 0.1524)
				(type default)
			)
			(layer "F.SilkS")
		)
		(fp_line
			(start -0.12065 -0.305054)
			(end -0.12065 -0.2794)
			(stroke
				(width 0.1)
				(type default)
			)
			(layer "F.Fab")
		)
		(fp_line
			(start -0.67945 -0.305054)
			(end -0.12065 -0.305054)
			(stroke
				(width 0.1)
				(type default)
			)
			(layer "F.Fab")
		)
		(fp_line
			(start 0.67945 -0.3048)
			(end 0.67945 0.3048)
			(stroke
				(width 0.1)
				(type default)
			)
			(layer "F.Fab")
		)
		(fp_line
			(start 0.12065 -0.3048)
			(end 0.67945 -0.3048)
			(stroke
				(width 0.1)
				(type default)
			)
			(layer "F.Fab")
		)
		(fp_line
			(start 0.12065 -0.2794)
			(end 0.12065 -0.3048)
			(stroke
				(width 0.1)
				(type default)
			)
			(layer "F.Fab")
		)
		(fp_line
			(start -0.12065 -0.2794)
			(end 0.12065 -0.2794)
			(stroke
				(width 0.1)
				(type default)
			)
			(layer "F.Fab")
		)
		(fp_line
			(start 0.120396 0.2794)
			(end -0.12065 0.2794)
			(stroke
				(width 0.1)
				(type default)
			)
			(layer "F.Fab")
		)
		(fp_line
			(start -0.12065 0.2794)
			(end -0.12065 0.3048)
			(stroke
				(width 0.1)
				(type default)
			)
			(layer "F.Fab")
		)
		(fp_line
			(start 0.67945 0.3048)
			(end 0.120396 0.3048)
			(stroke
				(width 0.1)
				(type default)
			)
			(layer "F.Fab")
		)
		(fp_line
			(start 0.120396 0.3048)
			(end 0.120396 0.2794)
			(stroke
				(width 0.1)
				(type default)
			)
			(layer "F.Fab")
		)
		(fp_line
			(start -0.12065 0.3048)
			(end -0.67945 0.3048)
			(stroke
				(width 0.1)
				(type default)
			)
			(layer "F.Fab")
		)
		(fp_line
			(start -0.67945 0.3048)
			(end -0.67945 -0.305054)
			(stroke
				(width 0.1)
				(type default)
			)
			(layer "F.Fab")
		)
		(pad "1" smd circle
			(at -0.40005 0 90)
			(size 0 0)
			(layers "F.Cu" "F.Mask" "F.Paste")
			(net "RST_CPU0_PERST1_N")
		)
		(pad "2" smd circle
			(at 0.40005 0 90)
			(size 0 0)
			(layers "F.Cu" "F.Mask" "F.Paste")
			(net "GND")
		)
	)
)
